(kicad_pcb
	(version 20260206)
	(generator "pcbnew")
	(generator_version "10.0")
	(general
		(thickness 1.6)
		(legacy_teardrops no)
	)
	(paper "A4")
	(title_block
		(title "Wiwynn_Tioga_Pass_MB.brd")
		(comment 1 "Tioga Pass / footprints 3209-3215 of 4770")
	)
	(layers
		(0 "F.Cu" signal "TOP")
		(4 "In1.Cu" signal "L2GND")
		(6 "In2.Cu" signal "L3")
		(8 "In3.Cu" signal "L4GND")
		(10 "In4.Cu" signal "L5")
		(12 "In5.Cu" signal "L6GND")
		(14 "In6.Cu" signal "L7VCC")
		(16 "In7.Cu" signal "L8VCC")
		(18 "In8.Cu" signal "L9GND")
		(20 "In9.Cu" signal "L10")
		(22 "In10.Cu" signal "L11GND")
		(24 "In11.Cu" signal "L12")
		(26 "In12.Cu" signal "L13GND")
		(2 "B.Cu" signal "BOTTOM")
		(9 "F.Adhes" user "F.Adhesive")
		(11 "B.Adhes" user "B.Adhesive")
		(13 "F.Paste" user "Package Geometry/Pastemask Top")
		(15 "B.Paste" user "Package Geometry/Pastemask Bottom")
		(5 "F.SilkS" user "Ref Des/Silkscreen Top")
		(7 "B.SilkS" user "Ref Des/Silkscreen Bottom")
		(1 "F.Mask" user "Board Geometry/Soldermask Top")
		(3 "B.Mask" user "Board Geometry/Soldermask Bottom")
		(17 "Dwgs.User" user "User.Drawings")
		(19 "Cmts.User" user "User.Comments")
		(21 "Eco1.User" user "User.Eco1")
		(23 "Eco2.User" user "User.Eco2")
		(25 "Edge.Cuts" user "Board Geometry/Outline")
		(27 "Margin" user)
		(31 "F.CrtYd" user "Package Geometry/Place Bound Top")
		(29 "B.CrtYd" user "Package Geometry/Place Bound Bottom")
		(35 "F.Fab" user "Ref Des/Assembly Top")
		(33 "B.Fab" user "Ref Des/Assembly Bottom")
	)
	(footprint ""
		(layer "B.Cu")
		(at 2.62382 -134.38632 90)
		(property "Reference" "C1A2"
			(at 0 0 90)
			(layer "B.SilkS")
			(hide yes)
			(effects
				(font
					(size 1.27 1.27)
				)
				(justify mirror)
			)
		)
		(property "Value" "*"
			(at -1.1811 -2.8194 90)
			(unlocked yes)
			(layer "B.Fab")
			(hide yes)
			(effects
				(font
					(size 1.27 1.016)
					(thickness 0.1524)
				)
				(justify mirror)
			)
		)
		(property "Device Type" "SC1U10V2KX-4-GP_SMD-BCG6-SC1U1A"
			(at -1.1811 -4.3434 90)
			(unlocked yes)
			(layer "B.Fab")
			(hide yes)
			(effects
				(font
					(size 1.27 1.016)
					(thickness 0.1524)
				)
				(justify mirror)
			)
		)
		(duplicate_pad_numbers_are_jumpers no)
		(fp_rect
			(start 0.4318 0.9525)
			(end -0.4318 -0.9525)
			(stroke
				(width 0)
				(type default)
			)
			(fill no)
			(layer "B.CrtYd")
		)
		(fp_rect
			(start 0.4318 0.9525)
			(end -0.4318 -0.9525)
			(stroke
				(width 0)
				(type default)
			)
			(fill no)
			(layer "B.Fab")
		)
		(pad "1" smd custom
			(at 0 -0.4445 270)
			(size 0.1524 0.1524)
			(layers "B.Cu" "B.Mask" "B.Paste")
			(net "P5V_STBY")
			(options
				(clearance outline)
				(anchor circle)
			)
			(primitives
				(gr_poly
					(pts
						(arc
							(start 0.3048 0.2032)
							(mid 0.275042 0.275042)
							(end 0.2032 0.3048)
						)
						(arc
							(start -0.2032 0.3048)
							(mid -0.275042 0.275042)
							(end -0.3048 0.2032)
						)
						(arc
							(start -0.3048 -0.2032)
							(mid -0.275042 -0.275042)
							(end -0.2032 -0.3048)
						)
						(arc
							(start 0.2032 -0.3048)
							(mid 0.275042 -0.275042)
							(end 0.3048 -0.2032)
						)
					)
					(width 0)
					(fill yes)
				)
			)
		)
		(pad "2" smd custom
			(at 0 0.4445 270)
			(size 0.1524 0.1524)
			(layers "B.Cu" "B.Mask" "B.Paste")
			(net "GND")
			(options
				(clearance outline)
				(anchor circle)
			)
			(primitives
				(gr_poly
					(pts
						(arc
							(start 0.3048 0.2032)
							(mid 0.275042 0.275042)
							(end 0.2032 0.3048)
						)
						(arc
							(start -0.2032 0.3048)
							(mid -0.275042 0.275042)
							(end -0.3048 0.2032)
						)
						(arc
							(start -0.3048 -0.2032)
							(mid -0.275042 -0.275042)
							(end -0.2032 -0.3048)
						)
						(arc
							(start 0.2032 -0.3048)
							(mid 0.275042 -0.275042)
							(end 0.3048 -0.2032)
						)
					)
					(width 0)
					(fill yes)
				)
			)
		)
	)
	(footprint ""
		(layer "B.Cu")
		(at 443.46368 -58.01614 -90)
		(property "Reference" "R1W41"
			(at 0.8382 -0.67818 270)
			(unlocked yes)
			(layer "B.SilkS")
			(effects
				(font
					(size 0.4064 0.254)
					(thickness 0.1524)
				)
				(justify left mirror)
			)
		)
		(property "Value" ""
			(at 0 0 90)
			(layer "B.Fab")
			(effects
				(font
					(size 1.27 1.27)
				)
				(justify mirror)
			)
		)
		(duplicate_pad_numbers_are_jumpers no)
		(fp_poly
			(pts
				(xy 0.2794 -0.1016) (xy -0.2794 -0.1016) (xy -0.2794 0.9906) (xy 0.2794 0.9906)
			)
			(stroke
				(width 0)
				(type default)
			)
			(fill no)
			(layer "B.CrtYd")
		)
		(fp_line
			(start -0.2794 0.9906)
			(end -0.2794 -0.1016)
			(stroke
				(width 0.1)
				(type default)
			)
			(layer "B.Fab")
		)
		(fp_line
			(start 0.2794 0.9906)
			(end -0.2794 0.9906)
			(stroke
				(width 0.1)
				(type default)
			)
			(layer "B.Fab")
		)
		(fp_line
			(start -0.2794 -0.1016)
			(end 0.2794 -0.1016)
			(stroke
				(width 0.1)
				(type default)
			)
			(layer "B.Fab")
		)
		(fp_line
			(start 0.2794 -0.1016)
			(end 0.2794 0.9906)
			(stroke
				(width 0.1)
				(type default)
			)
			(layer "B.Fab")
		)
		(pad "1" smd rect
			(at 0 0 90)
			(size 0.508 0.508)
			(layers "B.Cu" "B.Mask" "B.Paste")
			(net "GND")
		)
		(pad "2" smd rect
			(at 0 0.889 90)
			(size 0.508 0.508)
			(layers "B.Cu" "B.Mask" "B.Paste")
			(net "EXT_MDIO_I2C_SEL")
		)
		(zone
			(layer "B.Cu")
			(hatch none 0.5)
			(connect_pads
				(clearance 0)
			)
			(min_thickness 0.25)
			(keepout
				(tracks not_allowed)
				(vias allowed)
				(pads allowed)
				(copperpour not_allowed)
				(footprints allowed)
			)
			(placement
				(enabled no)
				(sheetname "")
			)
			(fill
				(thermal_gap 0.5)
				(thermal_bridge_width 0.5)
				(island_removal_mode 0)
			)
			(polygon
				(pts
					(xy 442.82868 -57.76214) (xy 442.82868 -58.27014) (xy 443.20968 -58.27014) (xy 443.20968 -57.76214)
				)
			)
		)
		(zone
			(layer "B.Cu")
			(hatch none 0.5)
			(connect_pads
				(clearance 0)
			)
			(min_thickness 0.25)
			(keepout
				(tracks allowed)
				(vias not_allowed)
				(pads allowed)
				(copperpour not_allowed)
				(footprints allowed)
			)
			(placement
				(enabled no)
				(sheetname "")
			)
			(fill
				(thermal_gap 0.5)
				(thermal_bridge_width 0.5)
				(island_removal_mode 0)
			)
			(polygon
				(pts
					(xy 443.20968 -57.76214) (xy 443.20968 -58.27014) (xy 442.82868 -58.27014) (xy 442.82868 -57.76214)
				)
			)
		)
	)
	(footprint ""
		(layer "B.Cu")
		(at 427.4185 -21.082 90)
		(property "Reference" "R1U10"
			(at 0 0 90)
			(layer "B.SilkS")
			(hide yes)
			(effects
				(font
					(size 1.27 1.27)
				)
				(justify mirror)
			)
		)
		(property "Value" ""
			(at 0 0 90)
			(layer "B.Fab")
			(effects
				(font
					(size 1.27 1.27)
				)
				(justify mirror)
			)
		)
		(duplicate_pad_numbers_are_jumpers no)
		(fp_poly
			(pts
				(xy 0.2794 -0.1016) (xy -0.2794 -0.1016) (xy -0.2794 0.9906) (xy 0.2794 0.9906)
			)
			(stroke
				(width 0)
				(type default)
			)
			(fill no)
			(layer "B.CrtYd")
		)
		(fp_line
			(start 0.2794 -0.1016)
			(end 0.2794 0.9906)
			(stroke
				(width 0.1)
				(type default)
			)
			(layer "B.Fab")
		)
		(fp_line
			(start -0.2794 -0.1016)
			(end 0.2794 -0.1016)
			(stroke
				(width 0.1)
				(type default)
			)
			(layer "B.Fab")
		)
		(fp_line
			(start 0.2794 0.9906)
			(end -0.2794 0.9906)
			(stroke
				(width 0.1)
				(type default)
			)
			(layer "B.Fab")
		)
		(fp_line
			(start -0.2794 0.9906)
			(end -0.2794 -0.1016)
			(stroke
				(width 0.1)
				(type default)
			)
			(layer "B.Fab")
		)
		(pad "1" smd rect
			(at 0 0 270)
			(size 0.508 0.508)
			(layers "B.Cu" "B.Mask" "B.Paste")
			(net "SMB_SMLINK0_STBY_LVC3_SDA_R")
		)
		(pad "2" smd rect
			(at 0 0.889 270)
			(size 0.508 0.508)
			(layers "B.Cu" "B.Mask" "B.Paste")
			(net "SMB_SMLINK0_STBY_LVC3_SDA")
		)
		(zone
			(layer "B.Cu")
			(hatch none 0.5)
			(connect_pads
				(clearance 0)
			)
			(min_thickness 0.25)
			(keepout
				(tracks allowed)
				(vias not_allowed)
				(pads allowed)
				(copperpour not_allowed)
				(footprints allowed)
			)
			(placement
				(enabled no)
				(sheetname "")
			)
			(fill
				(thermal_gap 0.5)
				(thermal_bridge_width 0.5)
				(island_removal_mode 0)
			)
			(polygon
				(pts
					(xy 427.6725 -21.336) (xy 427.6725 -20.828) (xy 428.0535 -20.828) (xy 428.0535 -21.336)
				)
			)
		)
		(zone
			(layer "B.Cu")
			(hatch none 0.5)
			(connect_pads
				(clearance 0)
			)
			(min_thickness 0.25)
			(keepout
				(tracks not_allowed)
				(vias allowed)
				(pads allowed)
				(copperpour not_allowed)
				(footprints allowed)
			)
			(placement
				(enabled no)
				(sheetname "")
			)
			(fill
				(thermal_gap 0.5)
				(thermal_bridge_width 0.5)
				(island_removal_mode 0)
			)
			(polygon
				(pts
					(xy 428.0535 -21.336) (xy 428.0535 -20.828) (xy 427.6725 -20.828) (xy 427.6725 -21.336)
				)
			)
		)
	)
	(footprint ""
		(layer "B.Cu")
		(at 30.452568 1.524 90)
		(property "Reference" "C9U10"
			(at 0 0 90)
			(layer "B.SilkS")
			(hide yes)
			(effects
				(font
					(size 1.27 1.27)
				)
				(justify mirror)
			)
		)
		(property "Value" ""
			(at 0 0 90)
			(layer "B.Fab")
			(effects
				(font
					(size 1.27 1.27)
				)
				(justify mirror)
			)
		)
		(duplicate_pad_numbers_are_jumpers no)
		(fp_poly
			(pts
				(xy -0.3048 -0.1016) (xy -0.3048 0.9906) (xy 0.3048 0.9906) (xy 0.3048 -0.1016)
			)
			(stroke
				(width 0)
				(type default)
			)
			(fill no)
			(layer "B.CrtYd")
		)
		(fp_line
			(start 0.3048 -0.1016)
			(end 0.3048 0.9906)
			(stroke
				(width 0.1)
				(type default)
			)
			(layer "B.Fab")
		)
		(fp_line
			(start -0.3048 -0.1016)
			(end 0.3048 -0.1016)
			(stroke
				(width 0.1)
				(type default)
			)
			(layer "B.Fab")
		)
		(fp_line
			(start 0.3048 0.9906)
			(end -0.3048 0.9906)
			(stroke
				(width 0.1)
				(type default)
			)
			(layer "B.Fab")
		)
		(fp_line
			(start -0.3048 0.9906)
			(end -0.3048 -0.1016)
			(stroke
				(width 0.1)
				(type default)
			)
			(layer "B.Fab")
		)
		(pad "1" smd rect
			(at 0 0 270)
			(size 0.508 0.508)
			(layers "B.Cu" "B.Mask" "B.Paste")
			(net "M_J_VREF")
		)
		(pad "2" smd rect
			(at 0 0.889 270)
			(size 0.508 0.508)
			(layers "B.Cu" "B.Mask" "B.Paste")
			(net "GND")
		)
		(zone
			(layer "B.Cu")
			(hatch none 0.5)
			(connect_pads
				(clearance 0)
			)
			(min_thickness 0.25)
			(keepout
				(tracks allowed)
				(vias not_allowed)
				(pads allowed)
				(copperpour not_allowed)
				(footprints allowed)
			)
			(placement
				(enabled no)
				(sheetname "")
			)
			(fill
				(thermal_gap 0.5)
				(thermal_bridge_width 0.5)
				(island_removal_mode 0)
			)
			(polygon
				(pts
					(xy 30.706568 1.27) (xy 30.706568 1.778) (xy 31.087568 1.778) (xy 31.087568 1.27)
				)
			)
		)
		(zone
			(layer "B.Cu")
			(hatch none 0.5)
			(connect_pads
				(clearance 0)
			)
			(min_thickness 0.25)
			(keepout
				(tracks not_allowed)
				(vias allowed)
				(pads allowed)
				(copperpour not_allowed)
				(footprints allowed)
			)
			(placement
				(enabled no)
				(sheetname "")
			)
			(fill
				(thermal_gap 0.5)
				(thermal_bridge_width 0.5)
				(island_removal_mode 0)
			)
			(polygon
				(pts
					(xy 31.087568 1.27) (xy 31.087568 1.778) (xy 30.706568 1.778) (xy 30.706568 1.27)
				)
			)
		)
	)
	(footprint ""
		(layer "B.Cu")
		(at 390.135364 -84.713572 180)
		(property "Reference" "R2L6"
			(at 0 0 0)
			(layer "B.SilkS")
			(hide yes)
			(effects
				(font
					(size 1.27 1.27)
				)
				(justify mirror)
			)
		)
		(property "Value" ""
			(at 0 0 0)
			(layer "B.Fab")
			(effects
				(font
					(size 1.27 1.27)
				)
				(justify mirror)
			)
		)
		(duplicate_pad_numbers_are_jumpers no)
		(fp_poly
			(pts
				(xy 0.2794 -0.1016) (xy -0.2794 -0.1016) (xy -0.2794 0.9906) (xy 0.2794 0.9906)
			)
			(stroke
				(width 0)
				(type default)
			)
			(fill no)
			(layer "B.CrtYd")
		)
		(fp_line
			(start 0.2794 0.9906)
			(end -0.2794 0.9906)
			(stroke
				(width 0.1)
				(type default)
			)
			(layer "B.Fab")
		)
		(fp_line
			(start 0.2794 -0.1016)
			(end 0.2794 0.9906)
			(stroke
				(width 0.1)
				(type default)
			)
			(layer "B.Fab")
		)
		(fp_line
			(start -0.2794 0.9906)
			(end -0.2794 -0.1016)
			(stroke
				(width 0.1)
				(type default)
			)
			(layer "B.Fab")
		)
		(fp_line
			(start -0.2794 -0.1016)
			(end 0.2794 -0.1016)
			(stroke
				(width 0.1)
				(type default)
			)
			(layer "B.Fab")
		)
		(pad "1" smd rect
			(at 0 0)
			(size 0.508 0.508)
			(layers "B.Cu" "B.Mask" "B.Paste")
			(net "P3V3_STBY")
		)
		(pad "2" smd rect
			(at 0 0.889)
			(size 0.508 0.508)
			(layers "B.Cu" "B.Mask" "B.Paste")
			(net "SGPIO_PCH_SSATA_CLOCK_R")
		)
		(zone
			(layer "B.Cu")
			(hatch none 0.5)
			(connect_pads
				(clearance 0)
			)
			(min_thickness 0.25)
			(keepout
				(tracks not_allowed)
				(vias allowed)
				(pads allowed)
				(copperpour not_allowed)
				(footprints allowed)
			)
			(placement
				(enabled no)
				(sheetname "")
			)
			(fill
				(thermal_gap 0.5)
				(thermal_bridge_width 0.5)
				(island_removal_mode 0)
			)
			(polygon
				(pts
					(xy 389.881364 -85.348572) (xy 390.389364 -85.348572) (xy 390.389364 -84.967572) (xy 389.881364 -84.967572)
				)
			)
		)
		(zone
			(layer "B.Cu")
			(hatch none 0.5)
			(connect_pads
				(clearance 0)
			)
			(min_thickness 0.25)
			(keepout
				(tracks allowed)
				(vias not_allowed)
				(pads allowed)
				(copperpour not_allowed)
				(footprints allowed)
			)
			(placement
				(enabled no)
				(sheetname "")
			)
			(fill
				(thermal_gap 0.5)
				(thermal_bridge_width 0.5)
				(island_removal_mode 0)
			)
			(polygon
				(pts
					(xy 389.881364 -84.967572) (xy 390.389364 -84.967572) (xy 390.389364 -85.348572) (xy 389.881364 -85.348572)
				)
			)
		)
	)
	(footprint ""
		(layer "B.Cu")
		(at 33.673796 -61.298582 90)
		(property "Reference" "C1E23"
			(at 0 0 90)
			(layer "B.SilkS")
			(hide yes)
			(effects
				(font
					(size 1.27 1.27)
				)
				(justify mirror)
			)
		)
		(property "Value" "*"
			(at -1.1811 -2.8194 90)
			(unlocked yes)
			(layer "B.Fab")
			(hide yes)
			(effects
				(font
					(size 1.27 1.016)
					(thickness 0.1524)
				)
				(justify mirror)
			)
		)
		(property "Device Type" "SC1U10V2KX-4-GP_SMD-BCG6-SC1U1A"
			(at -1.1811 -4.3434 90)
			(unlocked yes)
			(layer "B.Fab")
			(hide yes)
			(effects
				(font
					(size 1.27 1.016)
					(thickness 0.1524)
				)
				(justify mirror)
			)
		)
		(duplicate_pad_numbers_are_jumpers no)
		(fp_rect
			(start 0.4318 0.9525)
			(end -0.4318 -0.9525)
			(stroke
				(width 0)
				(type default)
			)
			(fill no)
			(layer "B.CrtYd")
		)
		(fp_rect
			(start 0.4318 0.9525)
			(end -0.4318 -0.9525)
			(stroke
				(width 0)
				(type default)
			)
			(fill no)
			(layer "B.Fab")
		)
		(pad "1" smd custom
			(at 0 -0.4445 270)
			(size 0.1524 0.1524)
			(layers "B.Cu" "B.Mask" "B.Paste")
			(net "P5V_STBY")
			(options
				(clearance outline)
				(anchor circle)
			)
			(primitives
				(gr_poly
					(pts
						(arc
							(start 0.3048 0.2032)
							(mid 0.275042 0.275042)
							(end 0.2032 0.3048)
						)
						(arc
							(start -0.2032 0.3048)
							(mid -0.275042 0.275042)
							(end -0.3048 0.2032)
						)
						(arc
							(start -0.3048 -0.2032)
							(mid -0.275042 -0.275042)
							(end -0.2032 -0.3048)
						)
						(arc
							(start 0.2032 -0.3048)
							(mid 0.275042 -0.275042)
							(end 0.3048 -0.2032)
						)
					)
					(width 0)
					(fill yes)
				)
			)
		)
		(pad "2" smd custom
			(at 0 0.4445 270)
			(size 0.1524 0.1524)
			(layers "B.Cu" "B.Mask" "B.Paste")
			(net "GND")
			(options
				(clearance outline)
				(anchor circle)
			)
			(primitives
				(gr_poly
					(pts
						(arc
							(start 0.3048 0.2032)
							(mid 0.275042 0.275042)
							(end 0.2032 0.3048)
						)
						(arc
							(start -0.2032 0.3048)
							(mid -0.275042 0.275042)
							(end -0.3048 0.2032)
						)
						(arc
							(start -0.3048 -0.2032)
							(mid -0.275042 -0.275042)
							(end -0.2032 -0.3048)
						)
						(arc
							(start 0.2032 -0.3048)
							(mid 0.275042 -0.275042)
							(end 0.3048 -0.2032)
						)
					)
					(width 0)
					(fill yes)
				)
			)
		)
	)
	(footprint ""
		(layer "B.Cu")
		(at 454.5838 -145.9738 -90)
		(property "Reference" "R9A14"
			(at 0 0 90)
			(layer "B.SilkS")
			(hide yes)
			(effects
				(font
					(size 1.27 1.27)
				)
				(justify mirror)
			)
		)
		(property "Value" ""
			(at 0 0 90)
			(layer "B.Fab")
			(effects
				(font
					(size 1.27 1.27)
				)
				(justify mirror)
			)
		)
		(duplicate_pad_numbers_are_jumpers no)
		(fp_poly
			(pts
				(xy 0.2794 -0.1016) (xy -0.2794 -0.1016) (xy -0.2794 0.9906) (xy 0.2794 0.9906)
			)
			(stroke
				(width 0)
				(type default)
			)
			(fill no)
			(layer "B.CrtYd")
		)
		(fp_line
			(start -0.2794 0.9906)
			(end -0.2794 -0.1016)
			(stroke
				(width 0.1)
				(type default)
			)
			(layer "B.Fab")
		)
		(fp_line
			(start 0.2794 0.9906)
			(end -0.2794 0.9906)
			(stroke
				(width 0.1)
				(type default)
			)
			(layer "B.Fab")
		)
		(fp_line
			(start -0.2794 -0.1016)
			(end 0.2794 -0.1016)
			(stroke
				(width 0.1)
				(type default)
			)
			(layer "B.Fab")
		)
		(fp_line
			(start 0.2794 -0.1016)
			(end 0.2794 0.9906)
			(stroke
				(width 0.1)
				(type default)
			)
			(layer "B.Fab")
		)
		(pad "1" smd rect
			(at 0 0 90)
			(size 0.508 0.508)
			(layers "B.Cu" "B.Mask" "B.Paste")
			(net "XDP_RST_CO_N")
		)
		(pad "2" smd rect
			(at 0 0.889 90)
			(size 0.508 0.508)
			(layers "B.Cu" "B.Mask" "B.Paste")
			(net "P3V3_STBY")
		)
		(zone
			(layer "B.Cu")
			(hatch none 0.5)
			(connect_pads
				(clearance 0)
			)
			(min_thickness 0.25)
			(keepout
				(tracks not_allowed)
				(vias allowed)
				(pads allowed)
				(copperpour not_allowed)
				(footprints allowed)
			)
			(placement
				(enabled no)
				(sheetname "")
			)
			(fill
				(thermal_gap 0.5)
				(thermal_bridge_width 0.5)
				(island_removal_mode 0)
			)
			(polygon
				(pts
					(xy 453.9488 -145.7198) (xy 453.9488 -146.2278) (xy 454.3298 -146.2278) (xy 454.3298 -145.7198)
				)
			)
		)
		(zone
			(layer "B.Cu")
			(hatch none 0.5)
			(connect_pads
				(clearance 0)
			)
			(min_thickness 0.25)
			(keepout
				(tracks allowed)
				(vias not_allowed)
				(pads allowed)
				(copperpour not_allowed)
				(footprints allowed)
			)
			(placement
				(enabled no)
				(sheetname "")
			)
			(fill
				(thermal_gap 0.5)
				(thermal_bridge_width 0.5)
				(island_removal_mode 0)
			)
			(polygon
				(pts
					(xy 454.3298 -145.7198) (xy 454.3298 -146.2278) (xy 453.9488 -146.2278) (xy 453.9488 -145.7198)
				)
			)
		)
	)
)
